(kicad_pcb
	(version 20221018)
	(generator pcbnew)
	(general
    (thickness 1.7403)
  )
	(paper "A4")
	(title_block
    (title "Data Center RDIMM DDR4 Tester")
    (date "2024-09-30")
    (rev "1.2.4")
		(comment 9 "footprints 77-86 of 690")
	)
	(layers
    (0 "F.Cu" signal)
    (1 "In1.Cu" power)
    (2 "In2.Cu" signal)
    (3 "In3.Cu" power)
    (4 "In4.Cu" power)
    (5 "In5.Cu" signal)
    (6 "In6.Cu" power)
    (7 "In7.Cu" signal)
    (8 "In8.Cu" power)
    (9 "In9.Cu" signal)
    (10 "In10.Cu" power)
    (31 "B.Cu" signal)
    (32 "B.Adhes" user "B.Adhesive")
    (33 "F.Adhes" user "F.Adhesive")
    (34 "B.Paste" user)
    (35 "F.Paste" user)
    (36 "B.SilkS" user "B.Silkscreen")
    (37 "F.SilkS" user "F.Silkscreen")
    (38 "B.Mask" user)
    (39 "F.Mask" user)
    (40 "Dwgs.User" user "User.Drawings")
    (41 "Cmts.User" user "User.Comments")
    (42 "Eco1.User" user "User.Eco1")
    (43 "Eco2.User" user "User.Eco2")
    (44 "Edge.Cuts" user)
    (45 "Margin" user)
    (46 "B.CrtYd" user "B.Courtyard")
    (47 "F.CrtYd" user "F.Courtyard")
    (48 "B.Fab" user)
    (49 "F.Fab" user)
  )
	(footprint "data-center-rdimm-ddr4-tester-footprints:R_0402_1005Metric" (layer "F.Cu")
    (at 136.5 98.25)
    (descr "Resistor SMD 0402")
    (tags "resistor SMD 0402")
    (property "Author" "Antmicro")
    (property "Current" "1A")
    (property "License" "Apache-2.0")
    (property "MPN" "ERJ2GE0R00X")
    (property "Manufacturer" "Panasonic")
    (property "Sheetfile" "supply.kicad_sch")
    (property "Sheetname" "Supply")
    (property "Tolerance" "")
    (property "Val" "0R")
    (property "ki_description" "0R resistor in 0402 package with unspecified tolerance")
    (attr smd)
    (fp_text reference "R55" (at -1.14 1.27) (layer "F.SilkS")
        (effects (font (size 0.7 0.7) (thickness 0.15)) (justify left bottom))
    )
    (fp_text value "R_0R_0402" (at 0 1.4) (layer "F.Fab") hide
        (effects (font (size 0.7 0.7) (thickness 0.15)) (justify left bottom))
    )
    (fp_text user "License: Apache-2.0" (at -0.95 5.169) (layer "F.Fab") hide
        (effects (font (size 0.7 0.7) (thickness 0.15)) (justify left bottom))
    )
    (fp_text user "${REFERENCE}" (at -0.95 3.168) (layer "F.Fab") hide
        (effects (font (size 0.7 0.7) (thickness 0.15)) (justify left bottom))
    )
    (fp_text user "Author: Antmicro" (at -0.95 4.169) (layer "F.Fab") hide
        (effects (font (size 0.7 0.7) (thickness 0.15)) (justify left bottom))
    )
    (fp_rect (start -0.93 -0.47) (end 0.93 0.47)
      (stroke (width 0.05) (type solid)) (fill none) (layer "F.CrtYd"))
    (fp_rect (start -0.5 -0.25) (end 0.5 0.25)
      (stroke (width 0.15) (type solid)) (fill none) (layer "F.Fab"))
    (pad "1" smd roundrect (at -0.485 0) (size 0.59 0.64) (layers "F.Cu" "F.Paste" "F.Mask") (roundrect_rratio 0.25)
      (net 649 "Net-(U10-INV)") (pintype "passive"))
    (pad "2" smd roundrect (at 0.485 0) (size 0.59 0.64) (layers "F.Cu" "F.Paste" "F.Mask") (roundrect_rratio 0.25)
      (net 9 "GND") (pintype "passive"))
  )
	(footprint "data-center-rdimm-ddr4-tester-footprints:Testpoint_smd_1mm" (layer "F.Cu")
    (at 142.625 93.8008)
    (property "Author" "Antmicro")
    (property "License" "Apache-2.0")
    (property "MPN" "")
    (property "Manufacturer" "")
    (property "Sheetfile" "supply.kicad_sch")
    (property "Sheetname" "Supply")
    (property "ki_description" "Test Point 1mm")
    (attr exclude_from_pos_files)
    (fp_text reference "TP6" (at 0.445 0.3292) (layer "F.SilkS")
        (effects (font (size 0.7 0.7) (thickness 0.15)) (justify left bottom))
    )
    (fp_text value "TP_1mm_SMD" (at 0 1.4) (layer "F.Fab") hide
        (effects (font (size 0.7 0.7) (thickness 0.15)) (justify left bottom))
    )
    (fp_text user "License: Apache-2.0" (at -0.5 5.2) (layer "F.Fab") hide
        (effects (font (size 0.7 0.7) (thickness 0.15)) (justify left bottom))
    )
    (fp_text user "${REFERENCE}" (at -0.5 2.8) (layer "F.Fab") hide
        (effects (font (size 0.7 0.7) (thickness 0.15)) (justify left bottom))
    )
    (fp_text user "Author: Antmicro" (at -0.5 4) (layer "F.Fab") hide
        (effects (font (size 0.7 0.7) (thickness 0.15)) (justify left bottom))
    )
    (pad "1" smd circle (at 0 0) (size 1 1) (layers "F.Cu" "F.Mask")
      (net 151 "/Supply/VCC_INT_EN") (pinfunction "1") (pintype "passive"))
  )
	(footprint "data-center-rdimm-ddr4-tester-footprints:Testpoint_smd_1mm" (layer "F.Cu")
    (at 142.625 95.25)
    (property "Author" "Antmicro")
    (property "License" "Apache-2.0")
    (property "MPN" "")
    (property "Manufacturer" "")
    (property "Sheetfile" "supply.kicad_sch")
    (property "Sheetname" "Supply")
    (property "ki_description" "Test Point 1mm")
    (attr exclude_from_pos_files)
    (fp_text reference "TP7" (at 0.505 0.44) (layer "F.SilkS")
        (effects (font (size 0.7 0.7) (thickness 0.15)) (justify left bottom))
    )
    (fp_text value "TP_1mm_SMD" (at 0 1.4) (layer "F.Fab") hide
        (effects (font (size 0.7 0.7) (thickness 0.15)) (justify left bottom))
    )
    (fp_text user "Author: Antmicro" (at -0.5 4) (layer "F.Fab") hide
        (effects (font (size 0.7 0.7) (thickness 0.15)) (justify left bottom))
    )
    (fp_text user "${REFERENCE}" (at -0.5 2.8) (layer "F.Fab") hide
        (effects (font (size 0.7 0.7) (thickness 0.15)) (justify left bottom))
    )
    (fp_text user "License: Apache-2.0" (at -0.5 5.2) (layer "F.Fab") hide
        (effects (font (size 0.7 0.7) (thickness 0.15)) (justify left bottom))
    )
    (pad "1" smd circle (at 0 0) (size 1 1) (layers "F.Cu" "F.Mask")
      (net 152 "/Supply/VCC_AUX_EN") (pinfunction "1") (pintype "passive"))
  )
	(footprint "data-center-rdimm-ddr4-tester-footprints:VSSOP-8_3x3mm_P0.65mm" (layer "F.Cu")
    (at 138.125 95.5)
    (property "Author" "Antmicro")
    (property "License" "Apache-2.0")
    (property "MPN" "LM3881MME/NOPB")
    (property "Manufacturer" "Texas Instruments")
    (property "Sheetfile" "supply.kicad_sch")
    (property "Sheetname" "Supply")
    (property "ki_description" "LM3881MME/NOPB")
    (attr smd)
    (fp_text reference "U10" (at -0.495 -1.92) (layer "F.SilkS")
        (effects (font (size 0.7 0.7) (thickness 0.15)) (justify left bottom))
    )
    (fp_text value "LM3881MME_NOPB" (at 0 2.9) (layer "F.Fab") hide
        (effects (font (size 0.7 0.7) (thickness 0.15)) (justify left bottom))
    )
    (fp_text user "License: Apache-2.0" (at -0.352 8.371) (layer "F.Fab") hide
        (effects (font (size 0.7 0.7) (thickness 0.15)) (justify left bottom))
    )
    (fp_text user "Author: Antmicro" (at -0.352 7.171) (layer "F.Fab") hide
        (effects (font (size 0.7 0.7) (thickness 0.15)) (justify left bottom))
    )
    (fp_text user "${REFERENCE}" (at -0.352 5.972) (layer "F.Fab") hide
        (effects (font (size 0.7 0.7) (thickness 0.15)) (justify left bottom))
    )
    (fp_line (start -1.6 -1.625) (end 1.554 -1.625)
      (stroke (width 0.12) (type solid)) (layer "F.SilkS"))
    (fp_line (start -1.496 1.625) (end 1.554 1.625)
      (stroke (width 0.12) (type solid)) (layer "F.SilkS"))
    (fp_circle (center -2.1 -1.438) (end -2.05 -1.438)
      (stroke (width 0.12) (type solid)) (fill solid) (layer "F.SilkS"))
    (fp_rect (start -3 -1.838) (end 3 1.862)
      (stroke (width 0.05) (type solid)) (fill none) (layer "F.CrtYd"))
    (fp_line (start -1.497 -1.502) (end 1.504 -1.502)
      (stroke (width 0.15) (type solid)) (layer "F.Fab"))
    (fp_line (start -1.497 1.5) (end -1.497 -1.502)
      (stroke (width 0.15) (type solid)) (layer "F.Fab"))
    (fp_line (start 1.504 -1.502) (end 1.504 1.5)
      (stroke (width 0.15) (type solid)) (layer "F.Fab"))
    (fp_line (start 1.504 1.5) (end -1.497 1.5)
      (stroke (width 0.15) (type solid)) (layer "F.Fab"))
    (pad "1" smd rect (at -2.096 -0.975) (size 1.556504 0.457986) (layers "F.Cu" "F.Paste" "F.Mask")
      (net 307 "5V0_SYS") (pinfunction "VCC") (pintype "power_in"))
    (pad "2" smd roundrect (at -2.096 -0.326) (size 1.556504 0.457986) (layers "F.Cu" "F.Paste" "F.Mask") (roundrect_rratio 0.5)
      (net 790 "/Supply/PWR_SEQ_EN") (pinfunction "EN") (pintype "passive"))
    (pad "3" smd roundrect (at -2.096 0.325) (size 1.556504 0.457986) (layers "F.Cu" "F.Paste" "F.Mask") (roundrect_rratio 0.5)
      (net 9 "GND") (pinfunction "GND") (pintype "power_in"))
    (pad "4" smd roundrect (at -2.096 0.974) (size 1.556504 0.457986) (layers "F.Cu" "F.Paste" "F.Mask") (roundrect_rratio 0.5)
      (net 649 "Net-(U10-INV)") (pinfunction "INV") (pintype "input"))
    (pad "5" smd roundrect (at 2.105 0.974) (size 1.556504 0.457986) (layers "F.Cu" "F.Paste" "F.Mask") (roundrect_rratio 0.5)
      (net 4 "Net-(U10-TADJ)") (pinfunction "TADJ") (pintype "passive"))
    (pad "6" smd roundrect (at 2.105 0.325) (size 1.556504 0.457986) (layers "F.Cu" "F.Paste" "F.Mask") (roundrect_rratio 0.5)
      (net 153 "/Supply/VCC_IO_EN") (pinfunction "FLAG3") (pintype "open_collector"))
    (pad "7" smd roundrect (at 2.105 -0.326) (size 1.556504 0.457986) (layers "F.Cu" "F.Paste" "F.Mask") (roundrect_rratio 0.5)
      (net 152 "/Supply/VCC_AUX_EN") (pinfunction "FLAG2") (pintype "open_collector"))
    (pad "8" smd roundrect (at 2.105 -0.975) (size 1.556504 0.457986) (layers "F.Cu" "F.Paste" "F.Mask") (roundrect_rratio 0.5)
      (net 151 "/Supply/VCC_INT_EN") (pinfunction "FLAG1") (pintype "open_collector"))
  )
	(footprint "data-center-rdimm-ddr4-tester-footprints:R_0402_1005Metric" (layer "F.Cu")
    (at 222.432 115.731)
    (descr "Resistor SMD 0402")
    (tags "resistor SMD 0402")
    (property "Author" "Antmicro")
    (property "License" "Apache-2.0")
    (property "MPN" "CR0402-FX-2201GLF")
    (property "Manufacturer" "Bourns")
    (property "Sheetfile" "config-spi.kicad_sch")
    (property "Sheetname" "Config SPI flash")
    (property "Tolerance" "1%")
    (property "Val" "2k2")
    (property "ki_description" "2k2 resistor in 0402 package with 1% tolerance")
    (attr smd)
    (fp_text reference "R14" (at -1.152 -0.431) (layer "F.SilkS")
        (effects (font (size 0.7 0.7) (thickness 0.15)) (justify left bottom))
    )
    (fp_text value "R_2k2_0402" (at 0 1.4) (layer "F.Fab") hide
        (effects (font (size 0.7 0.7) (thickness 0.15)) (justify left bottom))
    )
    (fp_text user "${REFERENCE}" (at -0.95 3.168) (layer "F.Fab") hide
        (effects (font (size 0.7 0.7) (thickness 0.15)) (justify left bottom))
    )
    (fp_text user "License: Apache-2.0" (at -0.95 5.169) (layer "F.Fab") hide
        (effects (font (size 0.7 0.7) (thickness 0.15)) (justify left bottom))
    )
    (fp_text user "Author: Antmicro" (at -0.95 4.169) (layer "F.Fab") hide
        (effects (font (size 0.7 0.7) (thickness 0.15)) (justify left bottom))
    )
    (fp_rect (start -0.93 -0.47) (end 0.93 0.47)
      (stroke (width 0.05) (type solid)) (fill none) (layer "F.CrtYd"))
    (fp_rect (start -0.5 -0.25) (end 0.5 0.25)
      (stroke (width 0.15) (type solid)) (fill none) (layer "F.Fab"))
    (pad "1" smd roundrect (at -0.485 0) (size 0.59 0.64) (layers "F.Cu" "F.Paste" "F.Mask") (roundrect_rratio 0.25)
      (net 143 "3V3_SYS") (pintype "passive"))
    (pad "2" smd roundrect (at 0.485 0) (size 0.59 0.64) (layers "F.Cu" "F.Paste" "F.Mask") (roundrect_rratio 0.25)
      (net 95 "FCS_B") (pintype "passive"))
  )
	(footprint "data-center-rdimm-ddr4-tester-footprints:R_0402_1005Metric" (layer "F.Cu")
    (at 137.325 121.315 90)
    (descr "Resistor SMD 0402")
    (tags "resistor SMD 0402")
    (property "Author" "Antmicro")
    (property "License" "Apache-2.0")
    (property "MPN" "CR0402-FX-2002GLF")
    (property "Manufacturer" "Bourns")
    (property "Sheetfile" "interfaces.kicad_sch")
    (property "Sheetname" "Interfaces")
    (property "Tolerance" "1%")
    (property "Val" "20k")
    (property "ki_description" "20k resistor in 0402 package with 1% tolerance")
    (attr smd)
    (fp_text reference "R133" (at -3.685 0.335 90) (layer "F.SilkS")
        (effects (font (size 0.7 0.7) (thickness 0.15)) (justify left bottom))
    )
    (fp_text value "R_20k_0402" (at 0 1.4 90) (layer "F.Fab") hide
        (effects (font (size 0.7 0.7) (thickness 0.15)) (justify left bottom))
    )
    (fp_text user "Author: Antmicro" (at -0.95 4.169 90) (layer "F.Fab") hide
        (effects (font (size 0.7 0.7) (thickness 0.15)) (justify left bottom))
    )
    (fp_text user "License: Apache-2.0" (at -0.95 5.169 90) (layer "F.Fab") hide
        (effects (font (size 0.7 0.7) (thickness 0.15)) (justify left bottom))
    )
    (fp_text user "${REFERENCE}" (at -0.95 3.168 90) (layer "F.Fab") hide
        (effects (font (size 0.7 0.7) (thickness 0.15)) (justify left bottom))
    )
    (fp_rect (start -0.93 -0.47) (end 0.93 0.47)
      (stroke (width 0.05) (type solid)) (fill none) (layer "F.CrtYd"))
    (fp_rect (start -0.5 -0.25) (end 0.5 0.25)
      (stroke (width 0.15) (type solid)) (fill none) (layer "F.Fab"))
    (pad "1" smd roundrect (at -0.485 0 90) (size 0.59 0.64) (layers "F.Cu" "F.Paste" "F.Mask") (roundrect_rratio 0.25)
      (net 143 "3V3_SYS") (pintype "passive"))
    (pad "2" smd roundrect (at 0.485 0 90) (size 0.59 0.64) (layers "F.Cu" "F.Paste" "F.Mask") (roundrect_rratio 0.25)
      (net 83 "SD_DAT0") (pintype "passive"))
  )
	(footprint "data-center-rdimm-ddr4-tester-footprints:R_0402_1005Metric" (layer "F.Cu")
    (at 131.8 121.325 90)
    (descr "Resistor SMD 0402")
    (tags "resistor SMD 0402")
    (property "Author" "Antmicro")
    (property "License" "Apache-2.0")
    (property "MPN" "CR0402-FX-2002GLF")
    (property "Manufacturer" "Bourns")
    (property "Sheetfile" "interfaces.kicad_sch")
    (property "Sheetname" "Interfaces")
    (property "Tolerance" "1%")
    (property "Val" "20k")
    (property "ki_description" "20k resistor in 0402 package with 1% tolerance")
    (attr smd)
    (fp_text reference "R137" (at -3.675 0.35 90) (layer "F.SilkS")
        (effects (font (size 0.7 0.7) (thickness 0.15)) (justify left bottom))
    )
    (fp_text value "R_20k_0402" (at 0 1.4 90) (layer "F.Fab") hide
        (effects (font (size 0.7 0.7) (thickness 0.15)) (justify left bottom))
    )
    (fp_text user "License: Apache-2.0" (at -0.95 5.169 90) (layer "F.Fab") hide
        (effects (font (size 0.7 0.7) (thickness 0.15)) (justify left bottom))
    )
    (fp_text user "${REFERENCE}" (at -0.95 3.168 90) (layer "F.Fab") hide
        (effects (font (size 0.7 0.7) (thickness 0.15)) (justify left bottom))
    )
    (fp_text user "Author: Antmicro" (at -0.95 4.169 90) (layer "F.Fab") hide
        (effects (font (size 0.7 0.7) (thickness 0.15)) (justify left bottom))
    )
    (fp_rect (start -0.93 -0.47) (end 0.93 0.47)
      (stroke (width 0.05) (type solid)) (fill none) (layer "F.CrtYd"))
    (fp_rect (start -0.5 -0.25) (end 0.5 0.25)
      (stroke (width 0.15) (type solid)) (fill none) (layer "F.Fab"))
    (pad "1" smd roundrect (at -0.485 0 90) (size 0.59 0.64) (layers "F.Cu" "F.Paste" "F.Mask") (roundrect_rratio 0.25)
      (net 143 "3V3_SYS") (pintype "passive"))
    (pad "2" smd roundrect (at 0.485 0 90) (size 0.59 0.64) (layers "F.Cu" "F.Paste" "F.Mask") (roundrect_rratio 0.25)
      (net 86 "SD_DAT3") (pintype "passive"))
  )
	(footprint "data-center-rdimm-ddr4-tester-footprints:R_0402_1005Metric" (layer "F.Cu")
    (at 130.7 121.325 90)
    (descr "Resistor SMD 0402")
    (tags "resistor SMD 0402")
    (property "Author" "Antmicro")
    (property "License" "Apache-2.0")
    (property "MPN" "CR0402-FX-2002GLF")
    (property "Manufacturer" "Bourns")
    (property "Sheetfile" "interfaces.kicad_sch")
    (property "Sheetname" "Interfaces")
    (property "Tolerance" "1%")
    (property "Val" "20k")
    (property "ki_description" "20k resistor in 0402 package with 1% tolerance")
    (attr smd)
    (fp_text reference "R138" (at -3.675 0.35 90) (layer "F.SilkS")
        (effects (font (size 0.7 0.7) (thickness 0.15)) (justify left bottom))
    )
    (fp_text value "R_20k_0402" (at 0 1.4 90) (layer "F.Fab") hide
        (effects (font (size 0.7 0.7) (thickness 0.15)) (justify left bottom))
    )
    (fp_text user "Author: Antmicro" (at -0.95 4.169 90) (layer "F.Fab") hide
        (effects (font (size 0.7 0.7) (thickness 0.15)) (justify left bottom))
    )
    (fp_text user "${REFERENCE}" (at -0.95 3.168 90) (layer "F.Fab") hide
        (effects (font (size 0.7 0.7) (thickness 0.15)) (justify left bottom))
    )
    (fp_text user "License: Apache-2.0" (at -0.95 5.169 90) (layer "F.Fab") hide
        (effects (font (size 0.7 0.7) (thickness 0.15)) (justify left bottom))
    )
    (fp_rect (start -0.93 -0.47) (end 0.93 0.47)
      (stroke (width 0.05) (type solid)) (fill none) (layer "F.CrtYd"))
    (fp_rect (start -0.5 -0.25) (end 0.5 0.25)
      (stroke (width 0.15) (type solid)) (fill none) (layer "F.Fab"))
    (pad "1" smd roundrect (at -0.485 0 90) (size 0.59 0.64) (layers "F.Cu" "F.Paste" "F.Mask") (roundrect_rratio 0.25)
      (net 143 "3V3_SYS") (pintype "passive"))
    (pad "2" smd roundrect (at 0.485 0 90) (size 0.59 0.64) (layers "F.Cu" "F.Paste" "F.Mask") (roundrect_rratio 0.25)
      (net 87 "SD_DAT2") (pintype "passive"))
  )
	(footprint "data-center-rdimm-ddr4-tester-footprints:C_0402_1005Metric" (layer "F.Cu")
    (at 138.286328 113.969157 180)
    (descr "Capacitor SMD 0402")
    (tags "capacitor SMD 0402")
    (property "Author" "Antmicro")
    (property "Dielectric" "X5R")
    (property "License" "Apache-2.0")
    (property "MPN" "GRM155R61H104KE14D")
    (property "Manufacturer" "Murata")
    (property "Sheetfile" "interfaces.kicad_sch")
    (property "Sheetname" "Interfaces")
    (property "Val" "100n")
    (property "Voltage" "50V")
    (property "ki_description" " ")
    (attr smd)
    (fp_text reference "C185" (at 1.936328 1.539157 180) (layer "F.SilkS")
        (effects (font (size 0.7 0.7) (thickness 0.15)) (justify left bottom))
    )
    (fp_text value "C_100n_0402" (at 0 1.4 180) (layer "F.Fab") hide
        (effects (font (size 0.7 0.7) (thickness 0.15)) (justify left bottom))
    )
    (fp_text user "Author: Antmicro" (at -0.932 4.17 180) (layer "F.Fab") hide
        (effects (font (size 0.7 0.7) (thickness 0.15)) (justify left bottom))
    )
    (fp_text user "${REFERENCE}" (at -0.932 3.168 180) (layer "F.Fab") hide
        (effects (font (size 0.7 0.7) (thickness 0.15)) (justify left bottom))
    )
    (fp_text user "License: Apache-2.0" (at -0.932 5.17 180) (layer "F.Fab") hide
        (effects (font (size 0.7 0.7) (thickness 0.15)) (justify left bottom))
    )
    (fp_rect (start -0.94 -0.47) (end 0.94 0.47)
      (stroke (width 0.05) (type solid)) (fill none) (layer "F.CrtYd"))
    (fp_rect (start -0.499 -0.249) (end 0.499 0.249)
      (stroke (width 0.15) (type solid)) (fill none) (layer "F.Fab"))
    (pad "1" smd roundrect (at -0.484 0 180) (size 0.59 0.64) (layers "F.Cu" "F.Paste" "F.Mask") (roundrect_rratio 0.25)
      (net 76 "Net-(U7-V_{PHY})") (pintype "passive"))
    (pad "2" smd roundrect (at 0.484 0 180) (size 0.59 0.64) (layers "F.Cu" "F.Paste" "F.Mask") (roundrect_rratio 0.25)
      (net 9 "GND") (pintype "passive"))
  )
	(footprint "data-center-rdimm-ddr4-tester-footprints:C_0402_1005Metric" (layer "F.Cu")
    (at 133.936328 104.832157 180)
    (descr "Capacitor SMD 0402")
    (tags "capacitor SMD 0402")
    (property "Author" "Antmicro")
    (property "Dielectric" "X5R")
    (property "License" "Apache-2.0")
    (property "MPN" "GRM155R61H104KE14D")
    (property "Manufacturer" "Murata")
    (property "Sheetfile" "interfaces.kicad_sch")
    (property "Sheetname" "Interfaces")
    (property "Val" "100n")
    (property "Voltage" "50V")
    (property "ki_description" " ")
    (attr smd)
    (fp_text reference "C188" (at 3.706328 -0.377843 180) (layer "F.SilkS")
        (effects (font (size 0.7 0.7) (thickness 0.15)) (justify left bottom))
    )
    (fp_text value "C_100n_0402" (at 0 1.4 180) (layer "F.Fab") hide
        (effects (font (size 0.7 0.7) (thickness 0.15)) (justify left bottom))
    )
    (fp_text user "${REFERENCE}" (at -0.932 3.168 180) (layer "F.Fab") hide
        (effects (font (size 0.7 0.7) (thickness 0.15)) (justify left bottom))
    )
    (fp_text user "Author: Antmicro" (at -0.932 4.17 180) (layer "F.Fab") hide
        (effects (font (size 0.7 0.7) (thickness 0.15)) (justify left bottom))
    )
    (fp_text user "License: Apache-2.0" (at -0.932 5.17 180) (layer "F.Fab") hide
        (effects (font (size 0.7 0.7) (thickness 0.15)) (justify left bottom))
    )
    (fp_rect (start -0.94 -0.47) (end 0.94 0.47)
      (stroke (width 0.05) (type solid)) (fill none) (layer "F.CrtYd"))
    (fp_rect (start -0.499 -0.249) (end 0.499 0.249)
      (stroke (width 0.15) (type solid)) (fill none) (layer "F.Fab"))
    (pad "1" smd roundrect (at -0.484 0 180) (size 0.59 0.64) (layers "F.Cu" "F.Paste" "F.Mask") (roundrect_rratio 0.25)
      (net 143 "3V3_SYS") (pintype "passive"))
    (pad "2" smd roundrect (at 0.484 0 180) (size 0.59 0.64) (layers "F.Cu" "F.Paste" "F.Mask") (roundrect_rratio 0.25)
      (net 9 "GND") (pintype "passive"))
  )
)
